(kicad_pcb
	(version 20260206)
	(generator "pcbnew")
	(generator_version "10.0")
	(general
		(thickness 1.6)
		(legacy_teardrops no)
	)
	(paper "A4")
	(title_block
		(title "01162023_DA0F0TEBIF0_F0T_Expander_BD_F_brd_V02_OCP.brd")
		(comment 1 "Grand Teton / footprints 749-754 of 9728")
	)
	(layers
		(0 "F.Cu" signal "TOP")
		(4 "In1.Cu" signal "GND")
		(6 "In2.Cu" signal "VCC")
		(8 "In3.Cu" signal "VCC1")
		(10 "In4.Cu" signal "GND1")
		(12 "In5.Cu" signal "IN1")
		(14 "In6.Cu" signal "GND2")
		(16 "In7.Cu" signal "IN2")
		(18 "In8.Cu" signal "GND3")
		(20 "In9.Cu" signal "IN3")
		(22 "In10.Cu" signal "GND4")
		(24 "In11.Cu" signal "IN4")
		(26 "In12.Cu" signal "GND5")
		(28 "In13.Cu" signal "IN5")
		(30 "In14.Cu" signal "GND6")
		(32 "In15.Cu" signal "IN6")
		(34 "In16.Cu" signal "GND7")
		(2 "B.Cu" signal "BOTTOM")
		(9 "F.Adhes" user "F.Adhesive")
		(11 "B.Adhes" user "B.Adhesive")
		(13 "F.Paste" user "Package Geometry/Pastemask Top")
		(15 "B.Paste" user "Package Geometry/Pastemask Bottom")
		(5 "F.SilkS" user "Ref Des/Silkscreen Top")
		(7 "B.SilkS" user "Ref Des/Silkscreen Bottom")
		(1 "F.Mask" user "Board Geometry/Soldermask Top")
		(3 "B.Mask" user "Board Geometry/Soldermask Bottom")
		(17 "Dwgs.User" user "User.Drawings")
		(19 "Cmts.User" user "User.Comments")
		(21 "Eco1.User" user "User.Eco1")
		(23 "Eco2.User" user "User.Eco2")
		(25 "Edge.Cuts" user "Board Geometry/Outline")
		(27 "Margin" user)
		(31 "F.CrtYd" user "Package Geometry/Place Bound Top")
		(29 "B.CrtYd" user "Package Geometry/Place Bound Bottom")
		(35 "F.Fab" user "Ref Des/Assembly Top")
		(33 "B.Fab" user "Ref Des/Assembly Bottom")
	)
	(footprint ""
		(layer "F.Cu")
		(at 440.371484 -96.811592 -90)
		(property "Reference" "R746"
			(at 0 0 270)
			(layer "F.SilkS")
			(hide yes)
			(effects
				(font
					(size 1.27 1.27)
				)
			)
		)
		(property "Value" ""
			(at 0 0 270)
			(layer "F.Fab")
			(effects
				(font
					(size 1.27 1.27)
				)
			)
		)
		(duplicate_pad_numbers_are_jumpers no)
		(fp_line
			(start -0.7874 0.4064)
			(end -0.7874 -0.4064)
			(stroke
				(width 0.1524)
				(type default)
			)
			(layer "F.SilkS")
		)
		(fp_line
			(start 0.7874 0.4064)
			(end -0.7874 0.4064)
			(stroke
				(width 0.1524)
				(type default)
			)
			(layer "F.SilkS")
		)
		(fp_line
			(start -0.7874 -0.4064)
			(end 0.7874 -0.4064)
			(stroke
				(width 0.1524)
				(type default)
			)
			(layer "F.SilkS")
		)
		(fp_line
			(start 0.7874 -0.4064)
			(end 0.7874 0.4064)
			(stroke
				(width 0.1524)
				(type default)
			)
			(layer "F.SilkS")
		)
		(fp_line
			(start -0.67945 0.3048)
			(end -0.67945 -0.305054)
			(stroke
				(width 0.1)
				(type default)
			)
			(layer "F.Fab")
		)
		(fp_line
			(start -0.12065 0.3048)
			(end -0.67945 0.3048)
			(stroke
				(width 0.1)
				(type default)
			)
			(layer "F.Fab")
		)
		(fp_line
			(start 0.120396 0.3048)
			(end 0.120396 0.2794)
			(stroke
				(width 0.1)
				(type default)
			)
			(layer "F.Fab")
		)
		(fp_line
			(start 0.67945 0.3048)
			(end 0.120396 0.3048)
			(stroke
				(width 0.1)
				(type default)
			)
			(layer "F.Fab")
		)
		(fp_line
			(start -0.12065 0.2794)
			(end -0.12065 0.3048)
			(stroke
				(width 0.1)
				(type default)
			)
			(layer "F.Fab")
		)
		(fp_line
			(start 0.120396 0.2794)
			(end -0.12065 0.2794)
			(stroke
				(width 0.1)
				(type default)
			)
			(layer "F.Fab")
		)
		(fp_line
			(start -0.12065 -0.2794)
			(end 0.12065 -0.2794)
			(stroke
				(width 0.1)
				(type default)
			)
			(layer "F.Fab")
		)
		(fp_line
			(start 0.12065 -0.2794)
			(end 0.12065 -0.3048)
			(stroke
				(width 0.1)
				(type default)
			)
			(layer "F.Fab")
		)
		(fp_line
			(start 0.12065 -0.3048)
			(end 0.67945 -0.3048)
			(stroke
				(width 0.1)
				(type default)
			)
			(layer "F.Fab")
		)
		(fp_line
			(start 0.67945 -0.3048)
			(end 0.67945 0.3048)
			(stroke
				(width 0.1)
				(type default)
			)
			(layer "F.Fab")
		)
		(fp_line
			(start -0.67945 -0.305054)
			(end -0.12065 -0.305054)
			(stroke
				(width 0.1)
				(type default)
			)
			(layer "F.Fab")
		)
		(fp_line
			(start -0.12065 -0.305054)
			(end -0.12065 -0.2794)
			(stroke
				(width 0.1)
				(type default)
			)
			(layer "F.Fab")
		)
		(pad "1" smd circle
			(at -0.40005 0 270)
			(size 0 0)
			(layers "F.Cu" "F.Mask" "F.Paste")
			(net "P3V3_AUX")
		)
		(pad "2" smd circle
			(at 0.40005 0 270)
			(size 0 0)
			(layers "F.Cu" "F.Mask" "F.Paste")
			(net "NIC_ADC_ALERT_N")
		)
	)
	(footprint ""
		(layer "F.Cu")
		(at 249.862848 -182.394606 -90)
		(property "Reference" "R5522"
			(at 0 0 270)
			(layer "F.SilkS")
			(hide yes)
			(effects
				(font
					(size 1.27 1.27)
				)
			)
		)
		(property "Value" ""
			(at 0 0 270)
			(layer "F.Fab")
			(effects
				(font
					(size 1.27 1.27)
				)
			)
		)
		(duplicate_pad_numbers_are_jumpers no)
		(fp_line
			(start -0.7874 0.4064)
			(end -0.7874 -0.4064)
			(stroke
				(width 0.1524)
				(type default)
			)
			(layer "F.SilkS")
		)
		(fp_line
			(start 0.7874 0.4064)
			(end -0.7874 0.4064)
			(stroke
				(width 0.1524)
				(type default)
			)
			(layer "F.SilkS")
		)
		(fp_line
			(start -0.7874 -0.4064)
			(end 0.7874 -0.4064)
			(stroke
				(width 0.1524)
				(type default)
			)
			(layer "F.SilkS")
		)
		(fp_line
			(start 0.7874 -0.4064)
			(end 0.7874 0.4064)
			(stroke
				(width 0.1524)
				(type default)
			)
			(layer "F.SilkS")
		)
		(fp_line
			(start -0.67945 0.3048)
			(end -0.67945 -0.305054)
			(stroke
				(width 0.1)
				(type default)
			)
			(layer "F.Fab")
		)
		(fp_line
			(start -0.12065 0.3048)
			(end -0.67945 0.3048)
			(stroke
				(width 0.1)
				(type default)
			)
			(layer "F.Fab")
		)
		(fp_line
			(start 0.120396 0.3048)
			(end 0.120396 0.2794)
			(stroke
				(width 0.1)
				(type default)
			)
			(layer "F.Fab")
		)
		(fp_line
			(start 0.67945 0.3048)
			(end 0.120396 0.3048)
			(stroke
				(width 0.1)
				(type default)
			)
			(layer "F.Fab")
		)
		(fp_line
			(start -0.12065 0.2794)
			(end -0.12065 0.3048)
			(stroke
				(width 0.1)
				(type default)
			)
			(layer "F.Fab")
		)
		(fp_line
			(start 0.120396 0.2794)
			(end -0.12065 0.2794)
			(stroke
				(width 0.1)
				(type default)
			)
			(layer "F.Fab")
		)
		(fp_line
			(start -0.12065 -0.2794)
			(end 0.12065 -0.2794)
			(stroke
				(width 0.1)
				(type default)
			)
			(layer "F.Fab")
		)
		(fp_line
			(start 0.12065 -0.2794)
			(end 0.12065 -0.3048)
			(stroke
				(width 0.1)
				(type default)
			)
			(layer "F.Fab")
		)
		(fp_line
			(start 0.12065 -0.3048)
			(end 0.67945 -0.3048)
			(stroke
				(width 0.1)
				(type default)
			)
			(layer "F.Fab")
		)
		(fp_line
			(start 0.67945 -0.3048)
			(end 0.67945 0.3048)
			(stroke
				(width 0.1)
				(type default)
			)
			(layer "F.Fab")
		)
		(fp_line
			(start -0.67945 -0.305054)
			(end -0.12065 -0.305054)
			(stroke
				(width 0.1)
				(type default)
			)
			(layer "F.Fab")
		)
		(fp_line
			(start -0.12065 -0.305054)
			(end -0.12065 -0.2794)
			(stroke
				(width 0.1)
				(type default)
			)
			(layer "F.Fab")
		)
		(pad "1" smd circle
			(at -0.40005 0 270)
			(size 0 0)
			(layers "F.Cu" "F.Mask" "F.Paste")
			(net "GND")
		)
		(pad "2" smd circle
			(at 0.40005 0 270)
			(size 0 0)
			(layers "F.Cu" "F.Mask" "F.Paste")
			(net "BIC_FWSPICK")
		)
	)
	(footprint ""
		(layer "F.Cu")
		(at 72.659494 -61.612526)
		(property "Reference" "PD29"
			(at -4.849368 -2.685288 0)
			(unlocked yes)
			(layer "F.SilkS")
			(effects
				(font
					(size 0.7874 0.5842)
					(thickness 0.1524)
				)
				(justify left)
			)
		)
		(property "Value" ""
			(at 0 0 0)
			(layer "F.Fab")
			(effects
				(font
					(size 1.27 1.27)
				)
			)
		)
		(duplicate_pad_numbers_are_jumpers no)
		(fp_line
			(start -3.656584 -1.970024)
			(end -3.656584 1.970024)
			(stroke
				(width 0.1524)
				(type default)
			)
			(layer "F.SilkS")
		)
		(fp_line
			(start -3.656584 1.970024)
			(end 4.240784 1.970024)
			(stroke
				(width 0.1524)
				(type default)
			)
			(layer "F.SilkS")
		)
		(fp_line
			(start 4.240784 -1.970024)
			(end -3.656584 -1.970024)
			(stroke
				(width 0.1524)
				(type default)
			)
			(layer "F.SilkS")
		)
		(fp_line
			(start 4.240784 1.970024)
			(end 4.240784 -1.970024)
			(stroke
				(width 0.1524)
				(type default)
			)
			(layer "F.SilkS")
		)
		(fp_poly
			(pts
				(xy 3.580384 1.970024) (xy 3.580384 -1.970024) (xy 4.240784 -1.970024) (xy 4.240784 1.970024)
			)
			(stroke
				(width 0)
				(type default)
			)
			(fill yes)
			(layer "F.SilkS")
		)
		(fp_line
			(start -2.3749 -1.970024)
			(end -2.3749 1.970024)
			(stroke
				(width 0.1)
				(type default)
			)
			(layer "F.Fab")
		)
		(fp_line
			(start -2.3749 1.970024)
			(end 2.3749 1.970024)
			(stroke
				(width 0.1)
				(type default)
			)
			(layer "F.Fab")
		)
		(fp_line
			(start 2.3749 -1.970024)
			(end -2.3749 -1.970024)
			(stroke
				(width 0.1)
				(type default)
			)
			(layer "F.Fab")
		)
		(fp_line
			(start 2.3749 1.970024)
			(end 2.3749 -1.970024)
			(stroke
				(width 0.1)
				(type default)
			)
			(layer "F.Fab")
		)
		(fp_text user "+"
			(at -4.9784 -0.23495 0)
			(unlocked yes)
			(layer "F.Fab")
			(effects
				(font
					(size 1.905 1.4224)
					(thickness 0.1524)
				)
				(justify left)
			)
		)
		(fp_text user "-"
			(at 4.1656 -0.23495 0)
			(unlocked yes)
			(layer "F.Fab")
			(effects
				(font
					(size 1.905 1.4224)
					(thickness 0.1524)
				)
				(justify left)
			)
		)
		(pad "A" smd rect
			(at -2.450084 0)
			(size 2.159 2.2606)
			(layers "F.Cu" "F.Mask" "F.Paste")
			(net "GND")
		)
		(pad "C" smd rect
			(at 2.450084 0)
			(size 2.159 2.2606)
			(layers "F.Cu" "F.Mask" "F.Paste")
			(net "P12V_AUX")
		)
	)
	(footprint ""
		(layer "F.Cu")
		(at 416.560508 -184.941718 180)
		(property "Reference" "R6445"
			(at 0 0 180)
			(layer "F.SilkS")
			(hide yes)
			(effects
				(font
					(size 1.27 1.27)
				)
			)
		)
		(property "Value" ""
			(at 0 0 180)
			(layer "F.Fab")
			(effects
				(font
					(size 1.27 1.27)
				)
			)
		)
		(duplicate_pad_numbers_are_jumpers no)
		(fp_line
			(start 0.7874 0.4064)
			(end -0.7874 0.4064)
			(stroke
				(width 0.1524)
				(type default)
			)
			(layer "F.SilkS")
		)
		(fp_line
			(start 0.7874 -0.4064)
			(end 0.7874 0.4064)
			(stroke
				(width 0.1524)
				(type default)
			)
			(layer "F.SilkS")
		)
		(fp_line
			(start -0.7874 0.4064)
			(end -0.7874 -0.4064)
			(stroke
				(width 0.1524)
				(type default)
			)
			(layer "F.SilkS")
		)
		(fp_line
			(start -0.7874 -0.4064)
			(end 0.7874 -0.4064)
			(stroke
				(width 0.1524)
				(type default)
			)
			(layer "F.SilkS")
		)
		(fp_line
			(start 0.67945 0.3048)
			(end 0.120396 0.3048)
			(stroke
				(width 0.1)
				(type default)
			)
			(layer "F.Fab")
		)
		(fp_line
			(start 0.67945 -0.3048)
			(end 0.67945 0.3048)
			(stroke
				(width 0.1)
				(type default)
			)
			(layer "F.Fab")
		)
		(fp_line
			(start 0.12065 -0.2794)
			(end 0.12065 -0.3048)
			(stroke
				(width 0.1)
				(type default)
			)
			(layer "F.Fab")
		)
		(fp_line
			(start 0.12065 -0.3048)
			(end 0.67945 -0.3048)
			(stroke
				(width 0.1)
				(type default)
			)
			(layer "F.Fab")
		)
		(fp_line
			(start 0.120396 0.3048)
			(end 0.120396 0.2794)
			(stroke
				(width 0.1)
				(type default)
			)
			(layer "F.Fab")
		)
		(fp_line
			(start 0.120396 0.2794)
			(end -0.12065 0.2794)
			(stroke
				(width 0.1)
				(type default)
			)
			(layer "F.Fab")
		)
		(fp_line
			(start -0.12065 0.3048)
			(end -0.67945 0.3048)
			(stroke
				(width 0.1)
				(type default)
			)
			(layer "F.Fab")
		)
		(fp_line
			(start -0.12065 0.2794)
			(end -0.12065 0.3048)
			(stroke
				(width 0.1)
				(type default)
			)
			(layer "F.Fab")
		)
		(fp_line
			(start -0.12065 -0.2794)
			(end 0.12065 -0.2794)
			(stroke
				(width 0.1)
				(type default)
			)
			(layer "F.Fab")
		)
		(fp_line
			(start -0.12065 -0.305054)
			(end -0.12065 -0.2794)
			(stroke
				(width 0.1)
				(type default)
			)
			(layer "F.Fab")
		)
		(fp_line
			(start -0.67945 0.3048)
			(end -0.67945 -0.305054)
			(stroke
				(width 0.1)
				(type default)
			)
			(layer "F.Fab")
		)
		(fp_line
			(start -0.67945 -0.305054)
			(end -0.12065 -0.305054)
			(stroke
				(width 0.1)
				(type default)
			)
			(layer "F.Fab")
		)
		(pad "1" smd circle
			(at -0.40005 0 180)
			(size 0 0)
			(layers "F.Cu" "F.Mask" "F.Paste")
			(net "FPGA_PEX3_MODE_SEL2_D_N")
		)
		(pad "2" smd circle
			(at 0.40005 0 180)
			(size 0 0)
			(layers "F.Cu" "F.Mask" "F.Paste")
			(net "P3V3_AUX")
		)
	)
	(footprint ""
		(layer "F.Cu")
		(at 283.248354 -166.302944 90)
		(property "Reference" "R249"
			(at 0 0 90)
			(layer "F.SilkS")
			(hide yes)
			(effects
				(font
					(size 1.27 1.27)
				)
			)
		)
		(property "Value" ""
			(at 0 0 90)
			(layer "F.Fab")
			(effects
				(font
					(size 1.27 1.27)
				)
			)
		)
		(duplicate_pad_numbers_are_jumpers no)
		(fp_line
			(start 0.7874 -0.4064)
			(end 0.7874 0.4064)
			(stroke
				(width 0.1524)
				(type default)
			)
			(layer "F.SilkS")
		)
		(fp_line
			(start -0.7874 -0.4064)
			(end 0.7874 -0.4064)
			(stroke
				(width 0.1524)
				(type default)
			)
			(layer "F.SilkS")
		)
		(fp_line
			(start 0.7874 0.4064)
			(end -0.7874 0.4064)
			(stroke
				(width 0.1524)
				(type default)
			)
			(layer "F.SilkS")
		)
		(fp_line
			(start -0.7874 0.4064)
			(end -0.7874 -0.4064)
			(stroke
				(width 0.1524)
				(type default)
			)
			(layer "F.SilkS")
		)
		(fp_line
			(start -0.12065 -0.305054)
			(end -0.12065 -0.2794)
			(stroke
				(width 0.1)
				(type default)
			)
			(layer "F.Fab")
		)
		(fp_line
			(start -0.67945 -0.305054)
			(end -0.12065 -0.305054)
			(stroke
				(width 0.1)
				(type default)
			)
			(layer "F.Fab")
		)
		(fp_line
			(start 0.67945 -0.3048)
			(end 0.67945 0.3048)
			(stroke
				(width 0.1)
				(type default)
			)
			(layer "F.Fab")
		)
		(fp_line
			(start 0.12065 -0.3048)
			(end 0.67945 -0.3048)
			(stroke
				(width 0.1)
				(type default)
			)
			(layer "F.Fab")
		)
		(fp_line
			(start 0.12065 -0.2794)
			(end 0.12065 -0.3048)
			(stroke
				(width 0.1)
				(type default)
			)
			(layer "F.Fab")
		)
		(fp_line
			(start -0.12065 -0.2794)
			(end 0.12065 -0.2794)
			(stroke
				(width 0.1)
				(type default)
			)
			(layer "F.Fab")
		)
		(fp_line
			(start 0.120396 0.2794)
			(end -0.12065 0.2794)
			(stroke
				(width 0.1)
				(type default)
			)
			(layer "F.Fab")
		)
		(fp_line
			(start -0.12065 0.2794)
			(end -0.12065 0.3048)
			(stroke
				(width 0.1)
				(type default)
			)
			(layer "F.Fab")
		)
		(fp_line
			(start 0.67945 0.3048)
			(end 0.120396 0.3048)
			(stroke
				(width 0.1)
				(type default)
			)
			(layer "F.Fab")
		)
		(fp_line
			(start 0.120396 0.3048)
			(end 0.120396 0.2794)
			(stroke
				(width 0.1)
				(type default)
			)
			(layer "F.Fab")
		)
		(fp_line
			(start -0.12065 0.3048)
			(end -0.67945 0.3048)
			(stroke
				(width 0.1)
				(type default)
			)
			(layer "F.Fab")
		)
		(fp_line
			(start -0.67945 0.3048)
			(end -0.67945 -0.305054)
			(stroke
				(width 0.1)
				(type default)
			)
			(layer "F.Fab")
		)
		(pad "1" smd circle
			(at -0.40005 0 90)
			(size 0 0)
			(layers "F.Cu" "F.Mask" "F.Paste")
			(net "RST_NIC4_PERST0_R_N")
		)
		(pad "2" smd circle
			(at 0.40005 0 90)
			(size 0 0)
			(layers "F.Cu" "F.Mask" "F.Paste")
			(net "RST_HP_NIC4_BUF_N")
		)
	)
	(footprint ""
		(layer "F.Cu")
		(at 136.870948 -145.189956 180)
		(property "Reference" "R712"
			(at 0 0 180)
			(layer "F.SilkS")
			(hide yes)
			(effects
				(font
					(size 1.27 1.27)
				)
			)
		)
		(property "Value" ""
			(at 0 0 180)
			(layer "F.Fab")
			(effects
				(font
					(size 1.27 1.27)
				)
			)
		)
		(duplicate_pad_numbers_are_jumpers no)
		(fp_line
			(start 0.7874 0.4064)
			(end -0.7874 0.4064)
			(stroke
				(width 0.1524)
				(type default)
			)
			(layer "F.SilkS")
		)
		(fp_line
			(start 0.7874 -0.4064)
			(end 0.7874 0.4064)
			(stroke
				(width 0.1524)
				(type default)
			)
			(layer "F.SilkS")
		)
		(fp_line
			(start -0.7874 0.4064)
			(end -0.7874 -0.4064)
			(stroke
				(width 0.1524)
				(type default)
			)
			(layer "F.SilkS")
		)
		(fp_line
			(start -0.7874 -0.4064)
			(end 0.7874 -0.4064)
			(stroke
				(width 0.1524)
				(type default)
			)
			(layer "F.SilkS")
		)
		(fp_line
			(start 0.67945 0.3048)
			(end 0.120396 0.3048)
			(stroke
				(width 0.1)
				(type default)
			)
			(layer "F.Fab")
		)
		(fp_line
			(start 0.67945 -0.3048)
			(end 0.67945 0.3048)
			(stroke
				(width 0.1)
				(type default)
			)
			(layer "F.Fab")
		)
		(fp_line
			(start 0.12065 -0.2794)
			(end 0.12065 -0.3048)
			(stroke
				(width 0.1)
				(type default)
			)
			(layer "F.Fab")
		)
		(fp_line
			(start 0.12065 -0.3048)
			(end 0.67945 -0.3048)
			(stroke
				(width 0.1)
				(type default)
			)
			(layer "F.Fab")
		)
		(fp_line
			(start 0.120396 0.3048)
			(end 0.120396 0.2794)
			(stroke
				(width 0.1)
				(type default)
			)
			(layer "F.Fab")
		)
		(fp_line
			(start 0.120396 0.2794)
			(end -0.12065 0.2794)
			(stroke
				(width 0.1)
				(type default)
			)
			(layer "F.Fab")
		)
		(fp_line
			(start -0.12065 0.3048)
			(end -0.67945 0.3048)
			(stroke
				(width 0.1)
				(type default)
			)
			(layer "F.Fab")
		)
		(fp_line
			(start -0.12065 0.2794)
			(end -0.12065 0.3048)
			(stroke
				(width 0.1)
				(type default)
			)
			(layer "F.Fab")
		)
		(fp_line
			(start -0.12065 -0.2794)
			(end 0.12065 -0.2794)
			(stroke
				(width 0.1)
				(type default)
			)
			(layer "F.Fab")
		)
		(fp_line
			(start -0.12065 -0.305054)
			(end -0.12065 -0.2794)
			(stroke
				(width 0.1)
				(type default)
			)
			(layer "F.Fab")
		)
		(fp_line
			(start -0.67945 0.3048)
			(end -0.67945 -0.305054)
			(stroke
				(width 0.1)
				(type default)
			)
			(layer "F.Fab")
		)
		(fp_line
			(start -0.67945 -0.305054)
			(end -0.12065 -0.305054)
			(stroke
				(width 0.1)
				(type default)
			)
			(layer "F.Fab")
		)
		(pad "1" smd circle
			(at -0.40005 0 180)
			(size 0 0)
			(layers "F.Cu" "F.Mask" "F.Paste")
			(net "P12V_NIC2")
		)
		(pad "2" smd circle
			(at 0.40005 0 180)
			(size 0 0)
			(layers "F.Cu" "F.Mask" "F.Paste")
			(net "P12V_NIC2_VIN_N")
		)
	)
)
